(kicad_pcb
	(version 20221018)
	(generator pcbnew)
	(general
    (thickness 1.518)
  )
	(paper "A4")
	(title_block
    (title "Kria K26 Devboard")
    (date "2024-03-26")
    (rev "1.2.5")
    (comment 1 "www.antmicro.com")
    (comment 2 "Antmicro Ltd.")
		(comment 9 "footprints 525-534 of 660")
	)
	(layers
    (0 "F.Cu" mixed)
    (1 "In1.Cu" power)
    (2 "In2.Cu" mixed)
    (3 "In3.Cu" power)
    (4 "In4.Cu" mixed)
    (5 "In5.Cu" power)
    (6 "In6.Cu" mixed)
    (31 "B.Cu" power)
    (32 "B.Adhes" user "B.Adhesive")
    (33 "F.Adhes" user "F.Adhesive")
    (34 "B.Paste" user)
    (35 "F.Paste" user)
    (36 "B.SilkS" user "B.Silkscreen")
    (37 "F.SilkS" user "F.Silkscreen")
    (38 "B.Mask" user)
    (39 "F.Mask" user)
    (40 "Dwgs.User" user "User.Drawings")
    (41 "Cmts.User" user "User.Comments")
    (42 "Eco1.User" user "User.Eco1")
    (43 "Eco2.User" user "User.Eco2")
    (44 "Edge.Cuts" user)
    (45 "Margin" user)
    (46 "B.CrtYd" user "B.Courtyard")
    (47 "F.CrtYd" user "F.Courtyard")
    (48 "B.Fab" user)
    (49 "F.Fab" user)
  )
	(footprint "kria-k26-devboard-footprints:C_0402_1005Metric" (layer "B.Cu")
    (at 116.606942 83.4)
    (descr "Capacitor SMD 0402")
    (tags "capacitor SMD 0402")
    (property "Author" "Antmicro")
    (property "Dielectric" "X5R")
    (property "License" "Apache-2.0")
    (property "MPN" "GRM155R61H104KE14D")
    (property "Manufacturer" "Murata")
    (property "Sheetfile" "usb.kicad_sch")
    (property "Sheetname" "USB")
    (property "Val" "100n")
    (property "Voltage" "50V")
    (property "ki_description" " ")
    (attr smd)
    (fp_text reference "C62" (at -0.896942 0.34 180) (layer "B.SilkS")
        (effects (font (size 0.7 0.7) (thickness 0.15)) (justify left bottom mirror))
    )
    (fp_text value "C_100n_0402" (at 0 -1.4 180) (layer "B.Fab") hide
        (effects (font (size 0.7 0.7) (thickness 0.15)) (justify left bottom mirror))
    )
    (fp_text user "License: Apache-2.0" (at -0.932 -5.17 180) (layer "B.Fab") hide
        (effects (font (size 0.7 0.7) (thickness 0.15)) (justify left bottom mirror))
    )
    (fp_text user "${REFERENCE}" (at -0.932 -3.168 180) (layer "B.Fab") hide
        (effects (font (size 0.7 0.7) (thickness 0.15)) (justify left bottom mirror))
    )
    (fp_text user "Author: Antmicro" (at -0.932 -4.17 180) (layer "B.Fab") hide
        (effects (font (size 0.7 0.7) (thickness 0.15)) (justify left bottom mirror))
    )
    (fp_rect (start -0.94 0.47) (end 0.94 -0.47)
      (stroke (width 0.05) (type solid)) (fill none) (layer "B.CrtYd"))
    (fp_rect (start -0.499 0.249) (end 0.499 -0.249)
      (stroke (width 0.15) (type solid)) (fill none) (layer "B.Fab"))
    (pad "1" smd roundrect (at -0.484 0) (size 0.59 0.64) (layers "B.Cu" "B.Paste" "B.Mask") (roundrect_rratio 0.25)
      (net 15 "PS_3V3") (pintype "passive"))
    (pad "2" smd roundrect (at 0.484 0) (size 0.59 0.64) (layers "B.Cu" "B.Paste" "B.Mask") (roundrect_rratio 0.25)
      (net 1 "GND") (pintype "passive"))
  )
	(footprint "kria-k26-devboard-footprints:C_0402_1005Metric" (layer "B.Cu")
    (at 127.666942 82.524862 180)
    (descr "Capacitor SMD 0402")
    (tags "capacitor SMD 0402")
    (property "Author" "Antmicro")
    (property "Dielectric" "X5R")
    (property "License" "Apache-2.0")
    (property "MPN" "GRM155R61H104KE14D")
    (property "Manufacturer" "Murata")
    (property "Sheetfile" "usb.kicad_sch")
    (property "Sheetname" "USB")
    (property "Val" "100n")
    (property "Voltage" "50V")
    (property "ki_description" " ")
    (attr smd)
    (fp_text reference "C48" (at 0.866942 -0.365138) (layer "B.SilkS")
        (effects (font (size 0.7 0.7) (thickness 0.15)) (justify left bottom mirror))
    )
    (fp_text value "C_100n_0402" (at 0 -1.4) (layer "B.Fab") hide
        (effects (font (size 0.7 0.7) (thickness 0.15)) (justify left bottom mirror))
    )
    (fp_text user "License: Apache-2.0" (at -0.932 -5.17) (layer "B.Fab") hide
        (effects (font (size 0.7 0.7) (thickness 0.15)) (justify left bottom mirror))
    )
    (fp_text user "${REFERENCE}" (at -0.932 -3.168) (layer "B.Fab") hide
        (effects (font (size 0.7 0.7) (thickness 0.15)) (justify left bottom mirror))
    )
    (fp_text user "Author: Antmicro" (at -0.932 -4.17) (layer "B.Fab") hide
        (effects (font (size 0.7 0.7) (thickness 0.15)) (justify left bottom mirror))
    )
    (fp_rect (start -0.94 0.47) (end 0.94 -0.47)
      (stroke (width 0.05) (type solid)) (fill none) (layer "B.CrtYd"))
    (fp_rect (start -0.499 0.249) (end 0.499 -0.249)
      (stroke (width 0.15) (type solid)) (fill none) (layer "B.Fab"))
    (pad "1" smd roundrect (at -0.484 0 180) (size 0.59 0.64) (layers "B.Cu" "B.Paste" "B.Mask") (roundrect_rratio 0.25)
      (net 18 "PS_1V2") (pintype "passive"))
    (pad "2" smd roundrect (at 0.484 0 180) (size 0.59 0.64) (layers "B.Cu" "B.Paste" "B.Mask") (roundrect_rratio 0.25)
      (net 1 "GND") (pintype "passive"))
  )
	(footprint "kria-k26-devboard-footprints:C_0402_1005Metric" (layer "B.Cu")
    (at 116.656942 80.5)
    (descr "Capacitor SMD 0402")
    (tags "capacitor SMD 0402")
    (property "Author" "Antmicro")
    (property "Dielectric" "X5R")
    (property "License" "Apache-2.0")
    (property "MPN" "GRM155R61H104KE14D")
    (property "Manufacturer" "Murata")
    (property "Sheetfile" "usb.kicad_sch")
    (property "Sheetname" "USB")
    (property "Val" "100n")
    (property "Voltage" "50V")
    (property "ki_description" " ")
    (attr smd)
    (fp_text reference "C58" (at -0.916942 0.43 180) (layer "B.SilkS")
        (effects (font (size 0.7 0.7) (thickness 0.15)) (justify left bottom mirror))
    )
    (fp_text value "C_100n_0402" (at 0 -1.4 180) (layer "B.Fab") hide
        (effects (font (size 0.7 0.7) (thickness 0.15)) (justify left bottom mirror))
    )
    (fp_text user "License: Apache-2.0" (at -0.932 -5.17 180) (layer "B.Fab") hide
        (effects (font (size 0.7 0.7) (thickness 0.15)) (justify left bottom mirror))
    )
    (fp_text user "Author: Antmicro" (at -0.932 -4.17 180) (layer "B.Fab") hide
        (effects (font (size 0.7 0.7) (thickness 0.15)) (justify left bottom mirror))
    )
    (fp_text user "${REFERENCE}" (at -0.932 -3.168 180) (layer "B.Fab") hide
        (effects (font (size 0.7 0.7) (thickness 0.15)) (justify left bottom mirror))
    )
    (fp_rect (start -0.94 0.47) (end 0.94 -0.47)
      (stroke (width 0.05) (type solid)) (fill none) (layer "B.CrtYd"))
    (fp_rect (start -0.499 0.249) (end 0.499 -0.249)
      (stroke (width 0.15) (type solid)) (fill none) (layer "B.Fab"))
    (pad "1" smd roundrect (at -0.484 0) (size 0.59 0.64) (layers "B.Cu" "B.Paste" "B.Mask") (roundrect_rratio 0.25)
      (net 15 "PS_3V3") (pintype "passive"))
    (pad "2" smd roundrect (at 0.484 0) (size 0.59 0.64) (layers "B.Cu" "B.Paste" "B.Mask") (roundrect_rratio 0.25)
      (net 1 "GND") (pintype "passive"))
  )
	(footprint "kria-k26-devboard-footprints:C_0402_1005Metric" (layer "B.Cu")
    (at 120.7 90 90)
    (descr "Capacitor SMD 0402")
    (tags "capacitor SMD 0402")
    (property "Author" "Antmicro")
    (property "Dielectric" "X5R")
    (property "License" "Apache-2.0")
    (property "MPN" "GRM155R61H104KE14D")
    (property "Manufacturer" "Murata")
    (property "Sheetfile" "usb.kicad_sch")
    (property "Sheetname" "USB")
    (property "Val" "100n")
    (property "Voltage" "50V")
    (property "ki_description" " ")
    (attr smd)
    (fp_text reference "C57" (at -0.84 0.39 270) (layer "B.SilkS")
        (effects (font (size 0.7 0.7) (thickness 0.15)) (justify left bottom mirror))
    )
    (fp_text value "C_100n_0402" (at 0 -1.4 270) (layer "B.Fab") hide
        (effects (font (size 0.7 0.7) (thickness 0.15)) (justify left bottom mirror))
    )
    (fp_text user "${REFERENCE}" (at -0.932 -3.168 270) (layer "B.Fab") hide
        (effects (font (size 0.7 0.7) (thickness 0.15)) (justify left bottom mirror))
    )
    (fp_text user "License: Apache-2.0" (at -0.932 -5.17 270) (layer "B.Fab") hide
        (effects (font (size 0.7 0.7) (thickness 0.15)) (justify left bottom mirror))
    )
    (fp_text user "Author: Antmicro" (at -0.932 -4.17 270) (layer "B.Fab") hide
        (effects (font (size 0.7 0.7) (thickness 0.15)) (justify left bottom mirror))
    )
    (fp_rect (start -0.94 0.47) (end 0.94 -0.47)
      (stroke (width 0.05) (type solid)) (fill none) (layer "B.CrtYd"))
    (fp_rect (start -0.499 0.249) (end 0.499 -0.249)
      (stroke (width 0.15) (type solid)) (fill none) (layer "B.Fab"))
    (pad "1" smd roundrect (at -0.484 0 90) (size 0.59 0.64) (layers "B.Cu" "B.Paste" "B.Mask") (roundrect_rratio 0.25)
      (net 18 "PS_1V2") (pintype "passive"))
    (pad "2" smd roundrect (at 0.484 0 90) (size 0.59 0.64) (layers "B.Cu" "B.Paste" "B.Mask") (roundrect_rratio 0.25)
      (net 1 "GND") (pintype "passive"))
  )
	(footprint "kria-k26-devboard-footprints:C_0402_1005Metric" (layer "B.Cu")
    (at 117.95 90.35 90)
    (descr "Capacitor SMD 0402")
    (tags "capacitor SMD 0402")
    (property "Author" "Antmicro")
    (property "Dielectric" "X5R")
    (property "License" "Apache-2.0")
    (property "MPN" "GRM155R61H104KE14D")
    (property "Manufacturer" "Murata")
    (property "Sheetfile" "usb.kicad_sch")
    (property "Sheetname" "USB")
    (property "Val" "100n")
    (property "Voltage" "50V")
    (property "ki_description" " ")
    (attr smd)
    (fp_text reference "C49" (at 0.5 -1.52 270) (layer "B.SilkS")
        (effects (font (size 0.7 0.7) (thickness 0.15)) (justify left bottom mirror))
    )
    (fp_text value "C_100n_0402" (at 0 -1.4 270) (layer "B.Fab") hide
        (effects (font (size 0.7 0.7) (thickness 0.15)) (justify left bottom mirror))
    )
    (fp_text user "Author: Antmicro" (at -0.932 -4.17 270) (layer "B.Fab") hide
        (effects (font (size 0.7 0.7) (thickness 0.15)) (justify left bottom mirror))
    )
    (fp_text user "${REFERENCE}" (at -0.932 -3.168 270) (layer "B.Fab") hide
        (effects (font (size 0.7 0.7) (thickness 0.15)) (justify left bottom mirror))
    )
    (fp_text user "License: Apache-2.0" (at -0.932 -5.17 270) (layer "B.Fab") hide
        (effects (font (size 0.7 0.7) (thickness 0.15)) (justify left bottom mirror))
    )
    (fp_rect (start -0.94 0.47) (end 0.94 -0.47)
      (stroke (width 0.05) (type solid)) (fill none) (layer "B.CrtYd"))
    (fp_rect (start -0.499 0.249) (end 0.499 -0.249)
      (stroke (width 0.15) (type solid)) (fill none) (layer "B.Fab"))
    (pad "1" smd roundrect (at -0.484 0 90) (size 0.59 0.64) (layers "B.Cu" "B.Paste" "B.Mask") (roundrect_rratio 0.25)
      (net 18 "PS_1V2") (pintype "passive"))
    (pad "2" smd roundrect (at 0.484 0 90) (size 0.59 0.64) (layers "B.Cu" "B.Paste" "B.Mask") (roundrect_rratio 0.25)
      (net 1 "GND") (pintype "passive"))
  )
	(footprint "kria-k26-devboard-footprints:C_0402_1005Metric" (layer "B.Cu")
    (at 124.906941 80.8 -90)
    (descr "Capacitor SMD 0402")
    (tags "capacitor SMD 0402")
    (property "Author" "Antmicro")
    (property "Dielectric" "X5R")
    (property "License" "Apache-2.0")
    (property "MPN" "GRM155R61H104KE14D")
    (property "Manufacturer" "Murata")
    (property "Sheetfile" "usb.kicad_sch")
    (property "Sheetname" "USB")
    (property "Val" "100n")
    (property "Voltage" "50V")
    (property "ki_description" " ")
    (attr smd)
    (fp_text reference "C60" (at -3.05 -0.443059 90) (layer "B.SilkS")
        (effects (font (size 0.7 0.7) (thickness 0.15)) (justify left bottom mirror))
    )
    (fp_text value "C_100n_0402" (at 0 -1.4 90) (layer "B.Fab") hide
        (effects (font (size 0.7 0.7) (thickness 0.15)) (justify left bottom mirror))
    )
    (fp_text user "License: Apache-2.0" (at -0.932 -5.17 90) (layer "B.Fab") hide
        (effects (font (size 0.7 0.7) (thickness 0.15)) (justify left bottom mirror))
    )
    (fp_text user "${REFERENCE}" (at -0.932 -3.168 90) (layer "B.Fab") hide
        (effects (font (size 0.7 0.7) (thickness 0.15)) (justify left bottom mirror))
    )
    (fp_text user "Author: Antmicro" (at -0.932 -4.17 90) (layer "B.Fab") hide
        (effects (font (size 0.7 0.7) (thickness 0.15)) (justify left bottom mirror))
    )
    (fp_rect (start -0.94 0.47) (end 0.94 -0.47)
      (stroke (width 0.05) (type solid)) (fill none) (layer "B.CrtYd"))
    (fp_rect (start -0.499 0.249) (end 0.499 -0.249)
      (stroke (width 0.15) (type solid)) (fill none) (layer "B.Fab"))
    (pad "1" smd roundrect (at -0.484 0 270) (size 0.59 0.64) (layers "B.Cu" "B.Paste" "B.Mask") (roundrect_rratio 0.25)
      (net 18 "PS_1V2") (pintype "passive"))
    (pad "2" smd roundrect (at 0.484 0 270) (size 0.59 0.64) (layers "B.Cu" "B.Paste" "B.Mask") (roundrect_rratio 0.25)
      (net 1 "GND") (pintype "passive"))
  )
	(footprint "kria-k26-devboard-footprints:C_0402_1005Metric" (layer "B.Cu")
    (at 122.125 80.8 -90)
    (descr "Capacitor SMD 0402")
    (tags "capacitor SMD 0402")
    (property "Author" "Antmicro")
    (property "Dielectric" "X5R")
    (property "License" "Apache-2.0")
    (property "MPN" "GRM155R61H104KE14D")
    (property "Manufacturer" "Murata")
    (property "Sheetfile" "usb.kicad_sch")
    (property "Sheetname" "USB")
    (property "Val" "100n")
    (property "Voltage" "50V")
    (property "ki_description" " ")
    (attr smd)
    (fp_text reference "C41" (at -3.04 -0.385 90) (layer "B.SilkS")
        (effects (font (size 0.7 0.7) (thickness 0.15)) (justify left bottom mirror))
    )
    (fp_text value "C_100n_0402" (at 0 -1.4 90) (layer "B.Fab") hide
        (effects (font (size 0.7 0.7) (thickness 0.15)) (justify left bottom mirror))
    )
    (fp_text user "Author: Antmicro" (at -0.932 -4.17 90) (layer "B.Fab") hide
        (effects (font (size 0.7 0.7) (thickness 0.15)) (justify left bottom mirror))
    )
    (fp_text user "${REFERENCE}" (at -0.932 -3.168 90) (layer "B.Fab") hide
        (effects (font (size 0.7 0.7) (thickness 0.15)) (justify left bottom mirror))
    )
    (fp_text user "License: Apache-2.0" (at -0.932 -5.17 90) (layer "B.Fab") hide
        (effects (font (size 0.7 0.7) (thickness 0.15)) (justify left bottom mirror))
    )
    (fp_rect (start -0.94 0.47) (end 0.94 -0.47)
      (stroke (width 0.05) (type solid)) (fill none) (layer "B.CrtYd"))
    (fp_rect (start -0.499 0.249) (end 0.499 -0.249)
      (stroke (width 0.15) (type solid)) (fill none) (layer "B.Fab"))
    (pad "1" smd roundrect (at -0.484 0 270) (size 0.59 0.64) (layers "B.Cu" "B.Paste" "B.Mask") (roundrect_rratio 0.25)
      (net 18 "PS_1V2") (pintype "passive"))
    (pad "2" smd roundrect (at 0.484 0 270) (size 0.59 0.64) (layers "B.Cu" "B.Paste" "B.Mask") (roundrect_rratio 0.25)
      (net 1 "GND") (pintype "passive"))
  )
	(footprint "kria-k26-devboard-footprints:C_0402_1005Metric" (layer "B.Cu")
    (at 95.1 75.5)
    (descr "Capacitor SMD 0402")
    (tags "capacitor SMD 0402")
    (property "Author" "Antmicro")
    (property "Dielectric" "X5R")
    (property "License" "Apache-2.0")
    (property "MPN" "GRM155R61H104KE14D")
    (property "Manufacturer" "Murata")
    (property "Sheetfile" "dp.kicad_sch")
    (property "Sheetname" "Display Port")
    (property "Val" "100n")
    (property "Voltage" "50V")
    (property "ki_description" " ")
    (attr smd)
    (fp_text reference "C5" (at 0.8 -0.55 180) (layer "B.SilkS")
        (effects (font (size 0.7 0.7) (thickness 0.15)) (justify left bottom mirror))
    )
    (fp_text value "C_100n_0402" (at 0 -1.4 180) (layer "B.Fab") hide
        (effects (font (size 0.7 0.7) (thickness 0.15)) (justify left bottom mirror))
    )
    (fp_text user "License: Apache-2.0" (at -0.932 -5.17 180) (layer "B.Fab") hide
        (effects (font (size 0.7 0.7) (thickness 0.15)) (justify left bottom mirror))
    )
    (fp_text user "${REFERENCE}" (at -0.932 -3.168 180) (layer "B.Fab") hide
        (effects (font (size 0.7 0.7) (thickness 0.15)) (justify left bottom mirror))
    )
    (fp_text user "Author: Antmicro" (at -0.932 -4.17 180) (layer "B.Fab") hide
        (effects (font (size 0.7 0.7) (thickness 0.15)) (justify left bottom mirror))
    )
    (fp_rect (start -0.94 0.47) (end 0.94 -0.47)
      (stroke (width 0.05) (type solid)) (fill none) (layer "B.CrtYd"))
    (fp_rect (start -0.499 0.249) (end 0.499 -0.249)
      (stroke (width 0.15) (type solid)) (fill none) (layer "B.Fab"))
    (pad "1" smd roundrect (at -0.484 0) (size 0.59 0.64) (layers "B.Cu" "B.Paste" "B.Mask") (roundrect_rratio 0.25)
      (net 15 "PS_3V3") (pintype "passive"))
    (pad "2" smd roundrect (at 0.484 0) (size 0.59 0.64) (layers "B.Cu" "B.Paste" "B.Mask") (roundrect_rratio 0.25)
      (net 1 "GND") (pintype "passive"))
  )
	(footprint "kria-k26-devboard-footprints:C_0402_1005Metric" (layer "B.Cu")
    (at 131.35 63.741421 90)
    (descr "Capacitor SMD 0402")
    (tags "capacitor SMD 0402")
    (property "Author" "Antmicro")
    (property "Dielectric" "X5R")
    (property "License" "Apache-2.0")
    (property "MPN" "GRM155R61H104KE14D")
    (property "Manufacturer" "Murata")
    (property "Sheetfile" "usb.kicad_sch")
    (property "Sheetname" "USB")
    (property "Val" "100n")
    (property "Voltage" "50V")
    (property "ki_description" " ")
    (attr smd)
    (fp_text reference "C75" (at 3.781421 0.36 270) (layer "B.SilkS")
        (effects (font (size 0.7 0.7) (thickness 0.15)) (justify left bottom mirror))
    )
    (fp_text value "C_100n_0402" (at 0 -1.4 270) (layer "B.Fab") hide
        (effects (font (size 0.7 0.7) (thickness 0.15)) (justify left bottom mirror))
    )
    (fp_text user "License: Apache-2.0" (at -0.932 -5.17 270) (layer "B.Fab") hide
        (effects (font (size 0.7 0.7) (thickness 0.15)) (justify left bottom mirror))
    )
    (fp_text user "Author: Antmicro" (at -0.932 -4.17 270) (layer "B.Fab") hide
        (effects (font (size 0.7 0.7) (thickness 0.15)) (justify left bottom mirror))
    )
    (fp_text user "${REFERENCE}" (at -0.932 -3.168 270) (layer "B.Fab") hide
        (effects (font (size 0.7 0.7) (thickness 0.15)) (justify left bottom mirror))
    )
    (fp_rect (start -0.94 0.47) (end 0.94 -0.47)
      (stroke (width 0.05) (type solid)) (fill none) (layer "B.CrtYd"))
    (fp_rect (start -0.499 0.249) (end 0.499 -0.249)
      (stroke (width 0.15) (type solid)) (fill none) (layer "B.Fab"))
    (pad "1" smd roundrect (at -0.484 0 90) (size 0.59 0.64) (layers "B.Cu" "B.Paste" "B.Mask") (roundrect_rratio 0.25)
      (net 64 "/USB/USB1_VBUS") (pintype "passive"))
    (pad "2" smd roundrect (at 0.484 0 90) (size 0.59 0.64) (layers "B.Cu" "B.Paste" "B.Mask") (roundrect_rratio 0.25)
      (net 1 "GND") (pintype "passive"))
  )
	(footprint "kria-k26-devboard-footprints:C_0402_1005Metric" (layer "B.Cu")
    (at 111.95 63.8 90)
    (descr "Capacitor SMD 0402")
    (tags "capacitor SMD 0402")
    (property "Author" "Antmicro")
    (property "Dielectric" "")
    (property "License" "Apache-2.0")
    (property "MPN" "CC0402MRX5R5BB106")
    (property "Manufacturer" "Yaego")
    (property "Sheetfile" "usb.kicad_sch")
    (property "Sheetname" "USB")
    (property "Val" "10u")
    (property "Voltage" "")
    (property "ki_description" " ")
    (attr smd)
    (fp_text reference "C81" (at 3.13 0.41 270) (layer "B.SilkS")
        (effects (font (size 0.7 0.7) (thickness 0.15)) (justify left bottom mirror))
    )
    (fp_text value "C_10u_0402" (at 0 -1.4 270) (layer "B.Fab") hide
        (effects (font (size 0.7 0.7) (thickness 0.15)) (justify left bottom mirror))
    )
    (fp_text user "Author: Antmicro" (at -0.932 -4.17 270) (layer "B.Fab") hide
        (effects (font (size 0.7 0.7) (thickness 0.15)) (justify left bottom mirror))
    )
    (fp_text user "License: Apache-2.0" (at -0.932 -5.17 270) (layer "B.Fab") hide
        (effects (font (size 0.7 0.7) (thickness 0.15)) (justify left bottom mirror))
    )
    (fp_text user "${REFERENCE}" (at -0.932 -3.168 270) (layer "B.Fab") hide
        (effects (font (size 0.7 0.7) (thickness 0.15)) (justify left bottom mirror))
    )
    (fp_rect (start -0.94 0.47) (end 0.94 -0.47)
      (stroke (width 0.05) (type solid)) (fill none) (layer "B.CrtYd"))
    (fp_rect (start -0.499 0.249) (end 0.499 -0.249)
      (stroke (width 0.15) (type solid)) (fill none) (layer "B.Fab"))
    (pad "1" smd roundrect (at -0.484 0 90) (size 0.59 0.64) (layers "B.Cu" "B.Paste" "B.Mask") (roundrect_rratio 0.25)
      (net 86 "/USB/USB3_VBUS") (pintype "passive"))
    (pad "2" smd roundrect (at 0.484 0 90) (size 0.59 0.64) (layers "B.Cu" "B.Paste" "B.Mask") (roundrect_rratio 0.25)
      (net 1 "GND") (pintype "passive"))
  )
)
